# T6G (Grand Teton) — schematic netlist excerpt (pin names and nets, part order shuffled) for the footprints in the layout excerpt that follows; sources: Cadence DE-HDL packaged netlist, KiCad conversion of 04192023_DAF0TMB3IC0_F0TG_MB_C_brd_V02_OCP.brd

R6331  Q_RES  9.53K 1% CHIP  pkg 0402LF  page 178 : A = USB_HUB2_TI_USB_R1_MRP_RBIAS ; B = GND

Q103  MOSFET_NCH_DUAL  PJT138K IC  pkg SOT363XD  page 126
  S1  = GND
  G1  = GPU_HMC_PRSNT_N
  D2  = GPU_HMC_PRSNT_ISO_N
  S2  = GND
  G2  = GPU_HMC_PRSNT
  D1  = GPU_HMC_PRSNT

(kicad_pcb
	(version 20260206)
	(generator "pcbnew")
	(generator_version "10.0")
	(general
		(thickness 1.6)
		(legacy_teardrops no)
	)
	(paper "A4")
	(title_block
		(title "04192023_DAF0TMB3IC0_F0TG_MB_C_brd_V02_OCP.brd")
		(comment 1 "Grand Teton / footprints 1459-1460 of 8354")
	)
	(layers
		(0 "F.Cu" signal "TOP")
		(4 "In1.Cu" signal "GND")
		(6 "In2.Cu" signal "IN1")
		(8 "In3.Cu" signal "GND1")
		(10 "In4.Cu" signal "IN2")
		(12 "In5.Cu" signal "GND2")
		(14 "In6.Cu" signal "IN3")
		(16 "In7.Cu" signal "GND3")
		(18 "In8.Cu" signal "VCC")
		(20 "In9.Cu" signal "VCC1")
		(22 "In10.Cu" signal "GND4")
		(24 "In11.Cu" signal "IN4")
		(26 "In12.Cu" signal "GND5")
		(28 "In13.Cu" signal "IN5")
		(30 "In14.Cu" signal "GND6")
		(32 "In15.Cu" signal "IN6")
		(34 "In16.Cu" signal "GND7")
		(2 "B.Cu" signal "BOTTOM")
		(9 "F.Adhes" user "F.Adhesive")
		(11 "B.Adhes" user "B.Adhesive")
		(13 "F.Paste" user "Package Geometry/Pastemask Top")
		(15 "B.Paste" user "Package Geometry/Pastemask Bottom")
		(5 "F.SilkS" user "Ref Des/Silkscreen Top")
		(7 "B.SilkS" user "Ref Des/Silkscreen Bottom")
		(1 "F.Mask" user "Board Geometry/Soldermask Top")
		(3 "B.Mask" user "Board Geometry/Soldermask Bottom")
		(17 "Dwgs.User" user "User.Drawings")
		(19 "Cmts.User" user "User.Comments")
		(21 "Eco1.User" user "User.Eco1")
		(23 "Eco2.User" user "User.Eco2")
		(25 "Edge.Cuts" user "Board Geometry/Outline")
		(27 "Margin" user)
		(31 "F.CrtYd" user "Package Geometry/Place Bound Top")
		(29 "B.CrtYd" user "Package Geometry/Place Bound Bottom")
		(35 "F.Fab" user "Ref Des/Assembly Top")
		(33 "B.Fab" user "Ref Des/Assembly Bottom")
	)
	(footprint ""
		(layer "F.Cu")
		(at 109.13999 -23.534878 -90)
		(property "Reference" "R6331"
			(at 0 0 270)
			(layer "F.SilkS")
			(hide yes)
			(effects
				(font
					(size 1.27 1.27)
				)
			)
		)
		(property "Value" ""
			(at 0 0 270)
			(layer "F.Fab")
			(effects
				(font
					(size 1.27 1.27)
				)
			)
		)
		(duplicate_pad_numbers_are_jumpers no)
		(fp_line
			(start -0.7874 0.4064)
			(end -0.7874 -0.4064)
			(stroke
				(width 0.1524)
				(type default)
			)
			(layer "F.SilkS")
		)
		(fp_line
			(start 0.7874 0.4064)
			(end -0.7874 0.4064)
			(stroke
				(width 0.1524)
				(type default)
			)
			(layer "F.SilkS")
		)
		(fp_line
			(start -0.7874 -0.4064)
			(end 0.7874 -0.4064)
			(stroke
				(width 0.1524)
				(type default)
			)
			(layer "F.SilkS")
		)
		(fp_line
			(start 0.7874 -0.4064)
			(end 0.7874 0.4064)
			(stroke
				(width 0.1524)
				(type default)
			)
			(layer "F.SilkS")
		)
		(fp_line
			(start -0.67945 0.3048)
			(end -0.67945 -0.305054)
			(stroke
				(width 0.1)
				(type default)
			)
			(layer "F.Fab")
		)
		(fp_line
			(start -0.12065 0.3048)
			(end -0.67945 0.3048)
			(stroke
				(width 0.1)
				(type default)
			)
			(layer "F.Fab")
		)
		(fp_line
			(start 0.120396 0.3048)
			(end 0.120396 0.2794)
			(stroke
				(width 0.1)
				(type default)
			)
			(layer "F.Fab")
		)
		(fp_line
			(start 0.67945 0.3048)
			(end 0.120396 0.3048)
			(stroke
				(width 0.1)
				(type default)
			)
			(layer "F.Fab")
		)
		(fp_line
			(start -0.12065 0.2794)
			(end -0.12065 0.3048)
			(stroke
				(width 0.1)
				(type default)
			)
			(layer "F.Fab")
		)
		(fp_line
			(start 0.120396 0.2794)
			(end -0.12065 0.2794)
			(stroke
				(width 0.1)
				(type default)
			)
			(layer "F.Fab")
		)
		(fp_line
			(start -0.12065 -0.2794)
			(end 0.12065 -0.2794)
			(stroke
				(width 0.1)
				(type default)
			)
			(layer "F.Fab")
		)
		(fp_line
			(start 0.12065 -0.2794)
			(end 0.12065 -0.3048)
			(stroke
				(width 0.1)
				(type default)
			)
			(layer "F.Fab")
		)
		(fp_line
			(start 0.12065 -0.3048)
			(end 0.67945 -0.3048)
			(stroke
				(width 0.1)
				(type default)
			)
			(layer "F.Fab")
		)
		(fp_line
			(start 0.67945 -0.3048)
			(end 0.67945 0.3048)
			(stroke
				(width 0.1)
				(type default)
			)
			(layer "F.Fab")
		)
		(fp_line
			(start -0.67945 -0.305054)
			(end -0.12065 -0.305054)
			(stroke
				(width 0.1)
				(type default)
			)
			(layer "F.Fab")
		)
		(fp_line
			(start -0.12065 -0.305054)
			(end -0.12065 -0.2794)
			(stroke
				(width 0.1)
				(type default)
			)
			(layer "F.Fab")
		)
		(pad "1" smd circle
			(at -0.40005 0 270)
			(size 0 0)
			(layers "F.Cu" "F.Mask" "F.Paste")
			(net "USB_HUB2_TI_USB_R1_MRP_RBIAS")
		)
		(pad "2" smd circle
			(at 0.40005 0 270)
			(size 0 0)
			(layers "F.Cu" "F.Mask" "F.Paste")
			(net "GND")
		)
	)
	(footprint ""
		(layer "F.Cu")
		(at 120.142 -418.338 -90)
		(property "Reference" "Q103"
			(at 4.610862 -0.59436 90)
			(unlocked yes)
			(layer "F.SilkS")
			(effects
				(font
					(size 0.7874 0.5842)
					(thickness 0.1524)
				)
				(justify left)
			)
		)
		(property "Value" ""
			(at 0 0 270)
			(layer "F.Fab")
			(effects
				(font
					(size 1.27 1.27)
				)
			)
		)
		(duplicate_pad_numbers_are_jumpers no)
		(fp_line
			(start -1.332738 1.100074)
			(end -1.332738 -1.100074)
			(stroke
				(width 0.1524)
				(type default)
			)
			(layer "F.SilkS")
		)
		(fp_line
			(start 1.332738 1.100074)
			(end -1.332738 1.100074)
			(stroke
				(width 0.1524)
				(type default)
			)
			(layer "F.SilkS")
		)
		(fp_line
			(start 0 -0.541274)
			(end 0.4826 -1.100074)
			(stroke
				(width 0.1524)
				(type default)
			)
			(layer "F.SilkS")
		)
		(fp_line
			(start -1.332738 -1.100074)
			(end -0.4826 -1.100074)
			(stroke
				(width 0.1524)
				(type default)
			)
			(layer "F.SilkS")
		)
		(fp_line
			(start -0.4826 -1.100074)
			(end 0 -0.541274)
			(stroke
				(width 0.1524)
				(type default)
			)
			(layer "F.SilkS")
		)
		(fp_line
			(start 0.4826 -1.100074)
			(end 1.332738 -1.100074)
			(stroke
				(width 0.1524)
				(type default)
			)
			(layer "F.SilkS")
		)
		(fp_line
			(start 1.332738 -1.100074)
			(end 1.332738 1.100074)
			(stroke
				(width 0.1524)
				(type default)
			)
			(layer "F.SilkS")
		)
		(fp_poly
			(pts
				(xy -1.696974 -1.588262) (xy -2.438908 -1.844548) (xy -1.937258 -2.33553)
			)
			(stroke
				(width 0)
				(type default)
			)
			(fill yes)
			(layer "F.SilkS")
		)
		(fp_line
			(start -0.674878 1.100074)
			(end -0.674878 -1.100074)
			(stroke
				(width 0.1)
				(type default)
			)
			(layer "F.Fab")
		)
		(fp_line
			(start 0.674878 1.100074)
			(end -0.674878 1.100074)
			(stroke
				(width 0.1)
				(type default)
			)
			(layer "F.Fab")
		)
		(fp_line
			(start -0.674878 -1.100074)
			(end 0.674878 -1.100074)
			(stroke
				(width 0.1)
				(type default)
			)
			(layer "F.Fab")
		)
		(fp_line
			(start 0.674878 -1.100074)
			(end 0.674878 1.100074)
			(stroke
				(width 0.1)
				(type default)
			)
			(layer "F.Fab")
		)
		(fp_poly
			(pts
				(xy -2.2352 -0.298958) (xy -2.2352 -1.001014) (xy -1.533144 -0.649986)
			)
			(stroke
				(width 0)
				(type default)
			)
			(fill yes)
			(layer "F.Fab")
		)
		(pad "1" smd rect
			(at -0.94996 -0.649986)
			(size 0.4318 0.508)
			(layers "F.Cu" "F.Mask" "F.Paste")
			(net "GND")
		)
		(pad "2" smd rect
			(at -0.94996 0)
			(size 0.4318 0.508)
			(layers "F.Cu" "F.Mask" "F.Paste")
			(net "GPU_HMC_PRSNT_N")
		)
		(pad "3" smd rect
			(at -0.94996 0.649986)
			(size 0.4318 0.508)
			(layers "F.Cu" "F.Mask" "F.Paste")
			(net "GPU_HMC_PRSNT_ISO_N")
		)
		(pad "4" smd rect
			(at 0.94996 0.649986)
			(size 0.4318 0.508)
			(layers "F.Cu" "F.Mask" "F.Paste")
			(net "GND")
		)
		(pad "5" smd rect
			(at 0.94996 0)
			(size 0.4318 0.508)
			(layers "F.Cu" "F.Mask" "F.Paste")
			(net "GPU_HMC_PRSNT")
		)
		(pad "6" smd rect
			(at 0.94996 -0.649986)
			(size 0.4318 0.508)
			(layers "F.Cu" "F.Mask" "F.Paste")
			(net "GPU_HMC_PRSNT")
		)
	)
)
